FILE_TYPE = MACRO_DRAWING;
SET COLOR_WIRE YELLOW;
SET COLOR_PROP ORANGE;
SET COLOR_DOT WHITE;
SET COLOR_ARC YELLOW;
SET COLOR_BODY GREEN;
SET COLOR_NOTE PURPLE;
SET PROP_DISPLAY VALUE;
SET PAGE_NUMBER P4;
FORCEADD QUANTA_TITLE_BLOCK_C..2
(-100 100);
FORCEPROP 1 LAST Q_TITLE TABLE OF CONTENT 3/3
J 0
(-9416 151);
DISPLAY 2.446809 (-9416 151);
PAINT GREEN (-9416 151);
FORCEPROP 1 LAST CUSTOM_TXT_CDS <CON_TC_SNM1>
J 0
(-7700 5675);
FORCEPROP 1 LAST CUSTOM_TXT_CDS <CON_TC_SNM2>
J 0
(-7700 5575);
FORCEPROP 1 LAST CUSTOM_TXT_CDS <CON_TC_SNM3>
J 0
(-7700 5475);
FORCEPROP 1 LAST CUSTOM_TXT_CDS <CON_TC_SNM4>
J 0
(-7700 5375);
FORCEPROP 1 LAST CUSTOM_TXT_CDS <CON_TC_SNM5>
J 0
(-7700 5275);
FORCEPROP 1 LAST CUSTOM_TXT_CDS <CON_TC_SNM6>
J 0
(-7700 5175);
FORCEPROP 1 LAST CUSTOM_TXT_CDS <CON_TC_SNM7>
J 0
(-7700 5075);
FORCEPROP 1 LAST CUSTOM_TXT_CDS <CON_TC_SNM8>
J 0
(-7700 4975);
FORCEPROP 1 LAST CUSTOM_TXT_CDS <CON_TC_SNM10>
J 0
(-7700 4775);
FORCEPROP 1 LAST CUSTOM_TXT_CDS <CON_TC_SNM12>
J 0
(-7700 4575);
FORCEPROP 1 LAST CUSTOM_TXT_CDS <CON_TC_SNM14>
J 0
(-7700 4375);
FORCEPROP 1 LAST CUSTOM_TXT_CDS <CON_TC_SNM15>
J 0
(-7700 4275);
FORCEPROP 1 LAST CUSTOM_TXT_CDS <CON_TC_SNM17>
J 0
(-7700 4075);
FORCEPROP 1 LAST CUSTOM_TXT_CDS <CON_TC_SNM18>
J 0
(-7700 3975);
FORCEPROP 1 LAST CUSTOM_TXT_CDS <CON_TC_SNM19>
J 0
(-7700 3875);
FORCEPROP 1 LAST CUSTOM_TXT_CDS <CON_TC_SNM20>
J 0
(-7700 3775);
FORCEPROP 1 LAST CUSTOM_TXT_CDS <CON_TC_SNM21>
J 0
(-7700 3675);
FORCEPROP 1 LAST CUSTOM_TXT_CDS <CON_TC_SNM22>
J 0
(-7700 3575);
FORCEPROP 1 LAST CUSTOM_TXT_CDS <CON_TC_SNM23>
J 0
(-7700 3475);
FORCEPROP 1 LAST CUSTOM_TXT_CDS <CON_TC_SNM24>
J 0
(-7700 3375);
FORCEPROP 1 LAST CUSTOM_TXT_CDS <CON_TC_SNM25>
J 0
(-7700 3275);
FORCEPROP 1 LAST CUSTOM_TXT_CDS <CON_TC_SNM26>
J 0
(-7700 3175);
FORCEPROP 1 LAST CUSTOM_TXT_CDS <CON_TC_SNM27>
J 0
(-7700 3075);
FORCEPROP 1 LAST CUSTOM_TXT_CDS <CON_TC_SNM28>
J 0
(-7700 2975);
FORCEPROP 1 LAST CUSTOM_TXT_CDS <CON_TC_SNM29>
J 0
(-7700 2875);
FORCEPROP 1 LAST CUSTOM_TXT_CDS <CON_TC_SNM30>
J 0
(-7700 2775);
FORCEPROP 1 LAST CUSTOM_TXT_CDS <CON_TC_SNM31>
J 0
(-7700 2675);
FORCEPROP 1 LAST CUSTOM_TXT_CDS <CON_TC_SNM32>
J 0
(-7700 2575);
FORCEPROP 1 LAST CUSTOM_TXT_CDS <CON_TC_SNM33>
J 0
(-7700 2475);
FORCEPROP 1 LAST CUSTOM_TXT_CDS <CON_TC_SNM34>
J 0
(-7700 2375);
FORCEPROP 1 LAST CUSTOM_TXT_CDS <CON_TC_SNM35>
J 0
(-7700 2275);
FORCEPROP 1 LAST CUSTOM_TXT_CDS <CON_TC_SNM36>
J 0
(-7700 2175);
FORCEPROP 1 LAST CUSTOM_TXT_CDS <CON_TC_SNM37>
J 0
(-7700 2075);
FORCEPROP 1 LAST CUSTOM_TXT_CDS <CON_TC_SNM38>
J 0
(-7700 1975);
FORCEPROP 1 LAST CUSTOM_TXT_CDS <CON_TC_SNM39>
J 0
(-7700 1875);
FORCEPROP 1 LAST CUSTOM_TXT_CDS <CON_TC_SNM40>
J 0
(-7700 1775);
FORCEPROP 1 LAST CUSTOM_TXT_CDS <CON_TC_SNM41>
J 0
(-5200 5675);
FORCEPROP 1 LAST CUSTOM_TXT_CDS <CON_TC_SNM42>
J 0
(-5200 5575);
FORCEPROP 1 LAST CUSTOM_TXT_CDS <CON_TC_SNM43>
J 0
(-5200 5475);
FORCEPROP 1 LAST CUSTOM_TXT_CDS <CON_TC_SNM44>
J 0
(-5200 5375);
FORCEPROP 1 LAST CUSTOM_TXT_CDS <CON_TC_SNM45>
J 0
(-5200 5275);
FORCEPROP 1 LAST CUSTOM_TXT_CDS <CON_TC_SNM46>
J 0
(-5200 5175);
FORCEPROP 1 LAST CUSTOM_TXT_CDS <CON_TC_SNM47>
J 0
(-5200 5075);
FORCEPROP 1 LAST CUSTOM_TXT_CDS <CON_TC_SNM48>
J 0
(-5200 4975);
FORCEPROP 1 LAST CUSTOM_TXT_CDS <CON_TC_SNM49>
J 0
(-5200 4875);
FORCEPROP 1 LAST CUSTOM_TXT_CDS <CON_TC_SNM50>
J 0
(-5200 4775);
FORCEPROP 1 LAST CUSTOM_TXT_CDS <CON_TC_SNM51>
J 0
(-5200 4675);
FORCEPROP 1 LAST CUSTOM_TXT_CDS <CON_TC_SNM52>
J 0
(-5200 4575);
FORCEPROP 1 LAST CUSTOM_TXT_CDS <CON_TC_SNM53>
J 0
(-5200 4475);
FORCEPROP 1 LAST CUSTOM_TXT_CDS <CON_TC_SNM54>
J 0
(-5200 4375);
FORCEPROP 1 LAST CUSTOM_TXT_CDS <CON_TC_SNM55>
J 0
(-5200 4275);
FORCEPROP 1 LAST CUSTOM_TXT_CDS <CON_TC_SNM56>
J 0
(-5200 4175);
FORCEPROP 1 LAST CUSTOM_TXT_CDS <CON_TC_SNM57>
J 0
(-5200 4075);
FORCEPROP 1 LAST CUSTOM_TXT_CDS <CON_TC_SNM58>
J 0
(-5200 3975);
FORCEPROP 1 LAST CUSTOM_TXT_CDS <CON_TC_SNM59>
J 0
(-5200 3875);
FORCEPROP 1 LAST CUSTOM_TXT_CDS <CON_TC_SNM60>
J 0
(-5200 3775);
FORCEPROP 1 LAST CUSTOM_TXT_CDS <CON_TC_SNM61>
J 0
(-5200 3675);
FORCEPROP 1 LAST CUSTOM_TXT_CDS <CON_TC_SNM62>
J 0
(-5200 3575);
FORCEPROP 1 LAST CUSTOM_TXT_CDS <CON_TC_SNM63>
J 0
(-5200 3475);
FORCEPROP 1 LAST CUSTOM_TXT_CDS <CON_TC_SNM64>
J 0
(-5200 3375);
FORCEPROP 1 LAST CUSTOM_TXT_CDS <CON_TC_SNM65>
J 0
(-5200 3275);
FORCEPROP 1 LAST CUSTOM_TXT_CDS <CON_TC_SNM66>
J 0
(-5200 3175);
FORCEPROP 1 LAST CUSTOM_TXT_CDS <CON_TC_SNM67>
J 0
(-5200 3075);
FORCEPROP 1 LAST CUSTOM_TXT_CDS <CON_TC_SNM68>
J 0
(-5200 2975);
FORCEPROP 1 LAST CUSTOM_TXT_CDS <CON_TC_SNM69>
J 0
(-5200 2875);
FORCEPROP 1 LAST CUSTOM_TXT_CDS <CON_TC_SNM70>
J 0
(-5200 2775);
FORCEPROP 1 LAST CUSTOM_TXT_CDS <CON_TC_SNM71>
J 0
(-5200 2675);
FORCEPROP 1 LAST CUSTOM_TXT_CDS <CON_TC_SNM72>
J 0
(-5200 2575);
FORCEPROP 1 LAST CUSTOM_TXT_CDS <CON_TC_SNM73>
J 0
(-5200 2475);
FORCEPROP 1 LAST CUSTOM_TXT_CDS <CON_TC_SNM74>
J 0
(-5200 2375);
FORCEPROP 1 LAST CUSTOM_TXT_CDS <CON_TC_SNM75>
J 0
(-5200 2275);
FORCEPROP 1 LAST CUSTOM_TXT_CDS <CON_TC_SNM76>
J 0
(-5200 2175);
FORCEPROP 1 LAST CUSTOM_TXT_CDS <CON_TC_SNM77>
J 0
(-5200 2075);
FORCEPROP 1 LAST CUSTOM_TXT_CDS <CON_TC_SNM78>
J 0
(-5200 1975);
FORCEPROP 1 LAST CUSTOM_TXT_CDS <CON_TC_SNM79>
J 0
(-5200 1875);
FORCEPROP 1 LAST CUSTOM_TXT_CDS <CON_TC_SNM80>
J 0
(-5200 1775);
FORCEPROP 1 LAST CUSTOM_TXT_CDS <CON_TC_SNM81>
J 0
(-2700 5675);
FORCEPROP 1 LAST CUSTOM_TXT_CDS <CON_TC_SNM82>
J 0
(-2700 5575);
FORCEPROP 1 LAST CUSTOM_TXT_CDS <CON_TC_SNM83>
J 0
(-2700 5475);
FORCEPROP 1 LAST CUSTOM_TXT_CDS <CON_TC_SNM84>
J 0
(-2700 5375);
FORCEPROP 1 LAST CUSTOM_TXT_CDS <CON_TC_SNM85>
J 0
(-2700 5275);
FORCEPROP 1 LAST CUSTOM_TXT_CDS <CON_TC_SNM86>
J 0
(-2700 5175);
FORCEPROP 1 LAST CUSTOM_TXT_CDS <CON_TC_SNM87>
J 0
(-2700 5075);
FORCEPROP 1 LAST CUSTOM_TXT_CDS <CON_TC_SNM88>
J 0
(-2700 4975);
FORCEPROP 1 LAST CUSTOM_TXT_CDS <CON_TC_SNM89>
J 0
(-2700 4875);
FORCEPROP 1 LAST CUSTOM_TXT_CDS <CON_TC_SNM90>
J 0
(-2700 4775);
FORCEPROP 1 LAST CUSTOM_TXT_CDS <CON_TC_SNM91>
J 0
(-2700 4675);
FORCEPROP 1 LAST CUSTOM_TXT_CDS <CON_TC_SNM92>
J 0
(-2700 4575);
FORCEPROP 1 LAST CUSTOM_TXT_CDS <CON_TC_SNM93>
J 0
(-2700 4475);
FORCEPROP 1 LAST CUSTOM_TXT_CDS <CON_TC_SNM94>
J 0
(-2700 4375);
FORCEPROP 1 LAST CUSTOM_TXT_CDS <CON_TC_SNM95>
J 0
(-2700 4275);
FORCEPROP 1 LAST CUSTOM_TXT_CDS <CON_TC_SNM96>
J 0
(-2700 4175);
FORCEPROP 1 LAST CUSTOM_TXT_CDS <CON_TC_SNM97>
J 0
(-2700 4075);
FORCEPROP 1 LAST CUSTOM_TXT_CDS <CON_TC_SNM98>
J 0
(-2700 3975);
FORCEPROP 1 LAST CUSTOM_TXT_CDS <CON_TC_SNM99>
J 0
(-2700 3875);
FORCEPROP 1 LAST CUSTOM_TXT_CDS <CON_TC_SNM100>
J 0
(-2700 3775);
FORCEPROP 1 LAST CUSTOM_TXT_CDS <CON_TC_SNM101>
J 0
(-2700 3675);
FORCEPROP 1 LAST CUSTOM_TXT_CDS <CON_TC_SNM102>
J 0
(-2700 3575);
FORCEPROP 1 LAST CUSTOM_TXT_CDS <CON_TC_SNM103>
J 0
(-2700 3475);
FORCEPROP 1 LAST CUSTOM_TXT_CDS <CON_TC_SNM104>
J 0
(-2700 3375);
FORCEPROP 1 LAST CUSTOM_TXT_CDS <CON_TC_SNM105>
J 0
(-2700 3275);
FORCEPROP 1 LAST CUSTOM_TXT_CDS <CON_TC_SNM106>
J 0
(-2700 3175);
FORCEPROP 1 LAST CUSTOM_TXT_CDS <CON_TC_SNM107>
J 0
(-2700 3075);
FORCEPROP 1 LAST CUSTOM_TXT_CDS <CON_TC_SNM108>
J 0
(-2700 2975);
FORCEPROP 1 LAST CUSTOM_TXT_CDS <CON_TC_SNM109>
J 0
(-2700 2875);
FORCEPROP 1 LAST CUSTOM_TXT_CDS <CON_TC_SNM110>
J 0
(-2700 2775);
FORCEPROP 1 LAST CUSTOM_TXT_CDS <CON_TC_SNM111>
J 0
(-2700 2675);
FORCEPROP 1 LAST CUSTOM_TXT_CDS <CON_TC_SNM112>
J 0
(-2700 2575);
FORCEPROP 1 LAST CUSTOM_TXT_CDS <CON_TC_SNM113>
J 0
(-2700 2475);
FORCEPROP 1 LAST CUSTOM_TXT_CDS <CON_TC_SNM114>
J 0
(-2700 2375);
FORCEPROP 1 LAST CUSTOM_TXT_CDS <CON_TC_SNM115>
J 0
(-2700 2275);
FORCEPROP 1 LAST CUSTOM_TXT_CDS <CON_TC_SNM116>
J 0
(-2700 2175);
FORCEPROP 1 LAST CUSTOM_TXT_CDS <CON_TC_SNM117>
J 0
(-2700 2075);
FORCEPROP 1 LAST CUSTOM_TXT_CDS <CON_TC_SNM118>
J 0
(-2700 1975);
FORCEPROP 1 LAST CUSTOM_TXT_CDS <CON_TC_SNM119>
J 0
(-2700 1875);
FORCEPROP 1 LAST CUSTOM_TXT_CDS <CON_TC_SNM120>
J 0
(-2700 1775);
FORCEPROP 1 LAST CUSTOM_TXT_CDS <CON_TC_SNO1>
J 2
(-7800 5675);
FORCEPROP 1 LAST CUSTOM_TXT_CDS <CON_TC_SNO2>
J 2
(-7800 5575);
FORCEPROP 1 LAST CUSTOM_TXT_CDS <CON_TC_SNO3>
J 2
(-7800 5475);
FORCEPROP 1 LAST CUSTOM_TXT_CDS <CON_TC_SNO4>
J 2
(-7800 5375);
FORCEPROP 1 LAST CUSTOM_TXT_CDS <CON_TC_SNO5>
J 2
(-7800 5275);
FORCEPROP 1 LAST CUSTOM_TXT_CDS <CON_TC_SNO7>
J 2
(-7800 5075);
FORCEPROP 1 LAST CUSTOM_TXT_CDS <CON_TC_SNO8>
J 2
(-7800 4975);
FORCEPROP 1 LAST CUSTOM_TXT_CDS <CON_TC_SNO9>
J 2
(-7800 4875);
FORCEPROP 1 LAST CUSTOM_TXT_CDS <CON_TC_SNO10>
J 2
(-7800 4775);
FORCEPROP 1 LAST CUSTOM_TXT_CDS <CON_TC_SNO11>
J 2
(-7800 4675);
FORCEPROP 1 LAST CUSTOM_TXT_CDS <CON_TC_SNO12>
J 2
(-7800 4575);
FORCEPROP 1 LAST CUSTOM_TXT_CDS <CON_TC_SNO13>
J 2
(-7800 4475);
FORCEPROP 1 LAST CUSTOM_TXT_CDS <CON_TC_SNO14>
J 2
(-7800 4375);
FORCEPROP 1 LAST CUSTOM_TXT_CDS <CON_TC_SNO15>
J 2
(-7800 4275);
FORCEPROP 1 LAST CUSTOM_TXT_CDS <CON_TC_SNO16>
J 2
(-7800 4175);
FORCEPROP 1 LAST CUSTOM_TXT_CDS <CON_TC_SNO17>
J 2
(-7800 4075);
FORCEPROP 1 LAST CUSTOM_TXT_CDS <CON_TC_SNO18>
J 2
(-7800 3975);
FORCEPROP 1 LAST CUSTOM_TXT_CDS <CON_TC_SNO19>
J 2
(-7800 3875);
FORCEPROP 1 LAST CUSTOM_TXT_CDS <CON_TC_SNO20>
J 2
(-7800 3775);
FORCEPROP 1 LAST CUSTOM_TXT_CDS <CON_TC_SNO21>
J 2
(-7800 3675);
FORCEPROP 1 LAST CUSTOM_TXT_CDS <CON_TC_SNO22>
J 2
(-7800 3575);
FORCEPROP 1 LAST CUSTOM_TXT_CDS <CON_TC_SNO23>
J 2
(-7800 3475);
FORCEPROP 1 LAST CUSTOM_TXT_CDS <CON_TC_SNO24>
J 2
(-7800 3375);
FORCEPROP 1 LAST CUSTOM_TXT_CDS <CON_TC_SNO25>
J 2
(-7800 3275);
FORCEPROP 1 LAST CUSTOM_TXT_CDS <CON_TC_SNO26>
J 2
(-7800 3175);
FORCEPROP 1 LAST CUSTOM_TXT_CDS <CON_TC_SNO27>
J 2
(-7800 3075);
FORCEPROP 1 LAST CUSTOM_TXT_CDS <CON_TC_SNO28>
J 2
(-7800 2975);
FORCEPROP 1 LAST CUSTOM_TXT_CDS <CON_TC_SNO29>
J 2
(-7800 2875);
FORCEPROP 1 LAST CUSTOM_TXT_CDS <CON_TC_SNO30>
J 2
(-7800 2775);
FORCEPROP 1 LAST CUSTOM_TXT_CDS <CON_TC_SNO31>
J 2
(-7800 2675);
FORCEPROP 1 LAST CUSTOM_TXT_CDS <CON_TC_SNO32>
J 2
(-7800 2575);
FORCEPROP 1 LAST CUSTOM_TXT_CDS <CON_TC_SNO33>
J 2
(-7800 2475);
FORCEPROP 1 LAST CUSTOM_TXT_CDS <CON_TC_SNO34>
J 2
(-7800 2375);
FORCEPROP 1 LAST CUSTOM_TXT_CDS <CON_TC_SNO35>
J 2
(-7800 2275);
FORCEPROP 1 LAST CUSTOM_TXT_CDS <CON_TC_SNO36>
J 2
(-7800 2175);
FORCEPROP 1 LAST CUSTOM_TXT_CDS <CON_TC_SNO37>
J 2
(-7800 2075);
FORCEPROP 1 LAST CUSTOM_TXT_CDS <CON_TC_SNO38>
J 2
(-7800 1975);
FORCEPROP 1 LAST CUSTOM_TXT_CDS <CON_TC_SNO39>
J 2
(-7800 1875);
FORCEPROP 1 LAST CUSTOM_TXT_CDS <CON_TC_SNO40>
J 2
(-7800 1775);
FORCEPROP 1 LAST CUSTOM_TXT_CDS <CON_TC_SNO41>
J 2
(-5300 5675);
FORCEPROP 1 LAST CUSTOM_TXT_CDS <CON_TC_SNO42>
J 2
(-5300 5575);
FORCEPROP 1 LAST CUSTOM_TXT_CDS <CON_TC_SNO43>
J 2
(-5300 5475);
FORCEPROP 1 LAST CUSTOM_TXT_CDS <CON_TC_SNO44>
J 2
(-5300 5375);
FORCEPROP 1 LAST CUSTOM_TXT_CDS <CON_TC_SNO45>
J 2
(-5300 5275);
FORCEPROP 1 LAST CUSTOM_TXT_CDS <CON_TC_SNO46>
J 2
(-5300 5175);
FORCEPROP 1 LAST CUSTOM_TXT_CDS <CON_TC_SNO47>
J 2
(-5300 5075);
FORCEPROP 1 LAST CUSTOM_TXT_CDS <CON_TC_SNO48>
J 2
(-5300 4975);
FORCEPROP 1 LAST CUSTOM_TXT_CDS <CON_TC_SNO49>
J 2
(-5300 4875);
FORCEPROP 1 LAST CUSTOM_TXT_CDS <CON_TC_SNO50>
J 2
(-5300 4775);
FORCEPROP 1 LAST CUSTOM_TXT_CDS <CON_TC_SNO51>
J 2
(-5300 4675);
FORCEPROP 1 LAST CUSTOM_TXT_CDS <CON_TC_SNO52>
J 2
(-5300 4575);
FORCEPROP 1 LAST CUSTOM_TXT_CDS <CON_TC_SNO53>
J 2
(-5300 4475);
FORCEPROP 1 LAST CUSTOM_TXT_CDS <CON_TC_SNO54>
J 2
(-5300 4375);
FORCEPROP 1 LAST CUSTOM_TXT_CDS <CON_TC_SNO55>
J 2
(-5300 4275);
FORCEPROP 1 LAST CUSTOM_TXT_CDS <CON_TC_SNO56>
J 2
(-5300 4175);
FORCEPROP 1 LAST CUSTOM_TXT_CDS <CON_TC_SNO57>
J 2
(-5300 4075);
FORCEPROP 1 LAST CUSTOM_TXT_CDS <CON_TC_SNO58>
J 2
(-5300 3975);
FORCEPROP 1 LAST CUSTOM_TXT_CDS <CON_TC_SNO59>
J 2
(-5300 3875);
FORCEPROP 1 LAST CUSTOM_TXT_CDS <CON_TC_SNO60>
J 2
(-5300 3775);
FORCEPROP 1 LAST CUSTOM_TXT_CDS <CON_TC_SNO61>
J 2
(-5300 3675);
FORCEPROP 1 LAST CUSTOM_TXT_CDS <CON_TC_SNO62>
J 2
(-5300 3575);
FORCEPROP 1 LAST CUSTOM_TXT_CDS <CON_TC_SNO63>
J 2
(-5300 3475);
FORCEPROP 1 LAST CUSTOM_TXT_CDS <CON_TC_SNO64>
J 2
(-5300 3375);
FORCEPROP 1 LAST CUSTOM_TXT_CDS <CON_TC_SNO65>
J 2
(-5300 3275);
FORCEPROP 1 LAST CUSTOM_TXT_CDS <CON_TC_SNO66>
J 2
(-5300 3175);
FORCEPROP 1 LAST CUSTOM_TXT_CDS <CON_TC_SNO67>
J 2
(-5300 3075);
FORCEPROP 1 LAST CUSTOM_TXT_CDS <CON_TC_SNO68>
J 2
(-5300 2975);
FORCEPROP 1 LAST CUSTOM_TXT_CDS <CON_TC_SNO69>
J 2
(-5300 2875);
FORCEPROP 1 LAST CUSTOM_TXT_CDS <CON_TC_SNO70>
J 2
(-5300 2775);
FORCEPROP 1 LAST CUSTOM_TXT_CDS <CON_TC_SNO71>
J 2
(-5300 2675);
FORCEPROP 1 LAST CUSTOM_TXT_CDS <CON_TC_SNO72>
J 2
(-5300 2575);
FORCEPROP 1 LAST CUSTOM_TXT_CDS <CON_TC_SNO73>
J 2
(-5300 2475);
FORCEPROP 1 LAST CUSTOM_TXT_CDS <CON_TC_SNO74>
J 2
(-5300 2375);
FORCEPROP 1 LAST CUSTOM_TXT_CDS <CON_TC_SNO75>
J 2
(-5300 2275);
FORCEPROP 1 LAST CUSTOM_TXT_CDS <CON_TC_SNO76>
J 2
(-5300 2175);
FORCEPROP 1 LAST CUSTOM_TXT_CDS <CON_TC_SNO77>
J 2
(-5300 2075);
FORCEPROP 1 LAST CUSTOM_TXT_CDS <CON_TC_SNO78>
J 2
(-5300 1975);
FORCEPROP 1 LAST CUSTOM_TXT_CDS <CON_TC_SNO79>
J 2
(-5300 1875);
FORCEPROP 1 LAST CUSTOM_TXT_CDS <CON_TC_SNO80>
J 2
(-5300 1775);
FORCEPROP 1 LAST CUSTOM_TXT_CDS <CON_TC_SNO81>
J 2
(-2800 5675);
FORCEPROP 1 LAST CUSTOM_TXT_CDS <CON_TC_SNO82>
J 2
(-2800 5575);
FORCEPROP 1 LAST CUSTOM_TXT_CDS <CON_TC_SNO83>
J 2
(-2800 5475);
FORCEPROP 1 LAST CUSTOM_TXT_CDS <CON_TC_SNO84>
J 2
(-2800 5375);
FORCEPROP 1 LAST CUSTOM_TXT_CDS <CON_TC_SNO85>
J 2
(-2800 5275);
FORCEPROP 1 LAST CUSTOM_TXT_CDS <CON_TC_SNO86>
J 2
(-2800 5175);
FORCEPROP 1 LAST CUSTOM_TXT_CDS <CON_TC_SNO87>
J 2
(-2800 5075);
FORCEPROP 1 LAST CUSTOM_TXT_CDS <CON_TC_SNO88>
J 2
(-2800 4975);
FORCEPROP 1 LAST CUSTOM_TXT_CDS <CON_TC_SNO89>
J 2
(-2800 4875);
FORCEPROP 1 LAST CUSTOM_TXT_CDS <CON_TC_SNO90>
J 2
(-2800 4775);
FORCEPROP 1 LAST CUSTOM_TXT_CDS <CON_TC_SNO91>
J 2
(-2800 4675);
FORCEPROP 1 LAST CUSTOM_TXT_CDS <CON_TC_SNO92>
J 2
(-2800 4575);
FORCEPROP 1 LAST CUSTOM_TXT_CDS <CON_TC_SNO93>
J 2
(-2800 4475);
FORCEPROP 1 LAST CUSTOM_TXT_CDS <CON_TC_SNO94>
J 2
(-2800 4375);
FORCEPROP 1 LAST CUSTOM_TXT_CDS <CON_TC_SNO95>
J 2
(-2800 4275);
FORCEPROP 1 LAST CUSTOM_TXT_CDS <CON_TC_SNO96>
J 2
(-2800 4175);
FORCEPROP 1 LAST CUSTOM_TXT_CDS <CON_TC_SNO97>
J 2
(-2800 4075);
FORCEPROP 1 LAST CUSTOM_TXT_CDS <CON_TC_SNO98>
J 2
(-2800 3975);
FORCEPROP 1 LAST CUSTOM_TXT_CDS <CON_TC_SNO99>
J 2
(-2800 3875);
FORCEPROP 1 LAST CUSTOM_TXT_CDS <CON_TC_SNO100>
J 2
(-2800 3775);
FORCEPROP 1 LAST CUSTOM_TXT_CDS <CON_TC_SNO101>
J 2
(-2800 3675);
FORCEPROP 1 LAST CUSTOM_TXT_CDS <CON_TC_SNO102>
J 2
(-2800 3575);
FORCEPROP 1 LAST CUSTOM_TXT_CDS <CON_TC_SNO103>
J 2
(-2800 3475);
FORCEPROP 1 LAST CUSTOM_TXT_CDS <CON_TC_SNO104>
J 2
(-2800 3375);
FORCEPROP 1 LAST CUSTOM_TXT_CDS <CON_TC_SNO105>
J 2
(-2800 3275);
FORCEPROP 1 LAST CUSTOM_TXT_CDS <CON_TC_SNO106>
J 2
(-2800 3175);
FORCEPROP 1 LAST CUSTOM_TXT_CDS <CON_TC_SNO107>
J 2
(-2800 3075);
FORCEPROP 1 LAST CUSTOM_TXT_CDS <CON_TC_SNO108>
J 2
(-2800 2975);
FORCEPROP 1 LAST CUSTOM_TXT_CDS <CON_TC_SNO109>
J 2
(-2800 2875);
FORCEPROP 1 LAST CUSTOM_TXT_CDS <CON_TC_SNO110>
J 2
(-2800 2775);
FORCEPROP 1 LAST CUSTOM_TXT_CDS <CON_TC_SNO111>
J 2
(-2800 2675);
FORCEPROP 1 LAST CUSTOM_TXT_CDS <CON_TC_SNO112>
J 2
(-2800 2575);
FORCEPROP 1 LAST CUSTOM_TXT_CDS <CON_TC_SNO113>
J 2
(-2800 2475);
FORCEPROP 1 LAST CUSTOM_TXT_CDS <CON_TC_SNO114>
J 2
(-2800 2375);
FORCEPROP 1 LAST CUSTOM_TXT_CDS <CON_TC_SNO115>
J 2
(-2800 2275);
FORCEPROP 1 LAST CUSTOM_TXT_CDS <CON_TC_SNO116>
J 2
(-2800 2175);
FORCEPROP 1 LAST CUSTOM_TXT_CDS <CON_TC_SNO117>
J 2
(-2800 2075);
FORCEPROP 1 LAST CUSTOM_TXT_CDS <CON_TC_SNO118>
J 2
(-2800 1975);
FORCEPROP 1 LAST CUSTOM_TXT_CDS <CON_TC_SNO119>
J 2
(-2800 1875);
FORCEPROP 1 LAST CUSTOM_TXT_CDS <CON_TC_SNO120>
J 2
(-2800 1775);
FORCEPROP 1 LAST CUSTOM_TXT_CDS <Q_NUMBER>
J 0
(-1500 200);
DISPLAY 1.212766 (-1500 200);
FORCEPROP 1 LAST CUSTOM_TXT_CDS <Q_PROJ>
J 0
(-2475 200);
DISPLAY 1.212766 (-2475 200);
FORCEPROP 1 LAST CUSTOM_TXT_CDS <Q_REV>
J 0
(-275 200);
DISPLAY 1.212766 (-275 200);
FORCEPROP 1 LAST CUSTOM_TXT_CDS <CON_LAST_MODIFIED>
J 0
(-2000 125);
DISPLAY 0.978723 (-2000 125);
FORCEPROP 1 LAST CUSTOM_TXT_CDS <CON_PAGE_NUM> OF <CON_TOTAL_PAGES>
J 0
(-538 113);
DISPLAY 0.978723 (-538 113);
FORCEPROP 1 LAST CUSTOM_TXT_CDS <CON_TC_SNO6>
J 2
(-7800 5175);
FORCEPROP 1 LAST CUSTOM_TXT_CDS <CON_TC_SNM9>
J 0
(-7700 4875);
FORCEPROP 1 LAST CUSTOM_TXT_CDS <CON_TC_SNM11>
J 0
(-7700 4675);
FORCEPROP 1 LAST CUSTOM_TXT_CDS <CON_TC_SNM13>
J 0
(-7700 4475);
FORCEPROP 1 LAST CUSTOM_TXT_CDS <CON_TC_SNM16>
J 0
(-7700 4175);
FORCEPROP 2 LAST CUSTOM_TXT_CDS <NAME_2>
J 0
(-3300 150);
DISPLAY 1.021277 (-3300 150);
FORCEPROP 2 LAST CUSTOM_TXT_CDS <NAME_1>
J 0
(-3300 275);
DISPLAY 1.021277 (-3300 275);
FORCEPROP 1 LAST Q_DEPT BU9
J 1
(-3851 149);
DISPLAY 1.957447 (-3851 149);
PAINT GREEN (-3851 149);
FORCEPROP 1 LAST TOC_SYMBOL TRUE
J 0
(-9274 6552);
DISPLAY 0.978723 (-9274 6552);
PAINT GREEN (-9274 6552);
DISPLAY INVISIBLE (-9274 6552);
FORCEPROP 2 LAST PAGE_BORDER TRUE
J 0
(-7990 5350);
DISPLAY 0.638298 (-7990 5350);
PAINT PINK (-7990 5350);
DISPLAY INVISIBLE (-7990 5350);
FORCEPROP 2 LAST CDS_LIB pure_quanta
J 0
(-100 100);
DISPLAY INVISIBLE (-100 100);
FORCEPROP 1 LAST COMMENT_BODY TRUE
J 0
(-1249 126);
DISPLAY 0.978723 (-1249 126);
PAINT GREEN (-1249 126);
DISPLAY INVISIBLE (-1249 126);
FORCEPROP 0 LAST CDS_CON_LAST_MODIFIED Mon Nov 15 20:05:01 2021
J 0
(-2000 125);
DISPLAY INVISIBLE (-2000 125);
FORCEPROP 2 LAST CUSTOM_TXT_CDS <XR_PAGE_TITLE>
J 0
(-7990 5350);
DISPLAY 0.638298 (-7990 5350);
PAINT PINK (-7990 5350);
DISPLAY INVISIBLE (-7990 5350);
FORCEPROP 2 LAST CDS_XR_PAGE_TITLE CR-4 : @T6G_MB_LIB.T6G(SCH_1):PAGE4
J 0
(-7990 5350);
DISPLAY 0.638298 (-7990 5350);
PAINT PINK (-7990 5350);
DISPLAY INVISIBLE (-7990 5350);
QUIT
